(kicad_pcb
	(version 20241229)
	(generator "pcbnew")
	(generator_version "9.0")
	(general
		(thickness 1.61)
		(legacy_teardrops no)
	)
	(paper "A3")
	(title_block
		(title "RDIMM DDR5 Tester")
		(date "2026-05-21")
		(rev "2.2.0")
		(company "Antmicro")
		(comment 9 "footprints 267-271 of 796")
	)
	(layers
		(0 "F.Cu" signal)
		(4 "In1.Cu" power)
		(6 "In2.Cu" mixed)
		(8 "In3.Cu" power)
		(10 "In4.Cu" mixed)
		(12 "In5.Cu" power)
		(14 "In6.Cu" mixed)
		(16 "In7.Cu" power)
		(18 "In8.Cu" power)
		(20 "In9.Cu" mixed)
		(22 "In10.Cu" power)
		(2 "B.Cu" signal)
		(9 "F.Adhes" user "F.Adhesive")
		(11 "B.Adhes" user "B.Adhesive")
		(13 "F.Paste" user)
		(15 "B.Paste" user)
		(5 "F.SilkS" user "F.Silkscreen")
		(7 "B.SilkS" user "B.Silkscreen")
		(1 "F.Mask" user)
		(3 "B.Mask" user)
		(17 "Dwgs.User" user "User.Drawings")
		(19 "Cmts.User" user "User.Comments")
		(21 "Eco1.User" user "User.Eco1")
		(23 "Eco2.User" user "User.Eco2")
		(25 "Edge.Cuts" user)
		(27 "Margin" user)
		(31 "F.CrtYd" user "F.Courtyard")
		(29 "B.CrtYd" user "B.Courtyard")
		(35 "F.Fab" user)
		(33 "B.Fab" user)
	)
	(footprint "antmicro-footprints:C_0402_1005Metric"
		(layer "F.Cu")
		(at 115.781 174.885 -90)
		(descr "Capacitor SMD 0402")
		(tags "capacitor SMD 0402")
		(property "Reference" "C126"
			(at -3.8275 -0.445 90)
			(layer "F.SilkS")
			(effects
				(font
					(size 0.7 0.7)
					(thickness 0.15)
				)
				(justify right bottom)
			)
		)
		(property "Value" "C_10u_6.3V_0402"
			(at -1.022927 2.155213 90)
			(layer "F.Fab")
			(effects
				(font
					(size 0.7 0.7)
					(thickness 0.15)
				)
				(justify right bottom)
			)
		)
		(property "Datasheet" "https://www.murata.com/products/productdetail?partno=GRM155R60J106ME15%23"
			(at 0 0 270)
			(layer "F.Fab")
			(hide yes)
			(effects
				(font
					(size 1.27 1.27)
					(thickness 0.15)
				)
			)
		)
		(property "MPN" "GRM155R60J106ME15D"
			(at 0 0 270)
			(unlocked yes)
			(layer "F.Fab")
			(hide yes)
			(effects
				(font
					(size 1 1)
					(thickness 0.15)
				)
			)
		)
		(property "Manufacturer" "Murata"
			(at 0 0 270)
			(unlocked yes)
			(layer "F.Fab")
			(hide yes)
			(effects
				(font
					(size 1 1)
					(thickness 0.15)
				)
			)
		)
		(property "License" "Apache-2.0"
			(at 0 0 270)
			(unlocked yes)
			(layer "F.Fab")
			(hide yes)
			(effects
				(font
					(size 1 1)
					(thickness 0.15)
				)
			)
		)
		(property "Author" "Antmicro"
			(at 0 0 270)
			(unlocked yes)
			(layer "F.Fab")
			(hide yes)
			(effects
				(font
					(size 1 1)
					(thickness 0.15)
				)
			)
		)
		(property "Val" "10u"
			(at 0 0 270)
			(unlocked yes)
			(layer "F.Fab")
			(hide yes)
			(effects
				(font
					(size 1 1)
					(thickness 0.15)
				)
			)
		)
		(property "Voltage" "6.3V"
			(at 0 0 270)
			(unlocked yes)
			(layer "F.Fab")
			(hide yes)
			(effects
				(font
					(size 1 1)
					(thickness 0.15)
				)
			)
		)
		(property "Dielectric" "X5R"
			(at 0 0 270)
			(unlocked yes)
			(layer "F.Fab")
			(hide yes)
			(effects
				(font
					(size 1 1)
					(thickness 0.15)
				)
			)
		)
		(sheetname "/HDMI + SD Card/")
		(sheetfile "hdmi-sd-card.kicad_sch")
		(attr smd)
		(fp_rect
			(start -0.925 -0.47)
			(end 0.925 0.47)
			(stroke
				(width 0.05)
				(type default)
			)
			(fill no)
			(layer "F.CrtYd")
		)
		(fp_line
			(start -0.494 0.248)
			(end -0.494 -0.25)
			(stroke
				(width 0.15)
				(type solid)
			)
			(layer "F.Fab")
		)
		(fp_line
			(start 0.504 0.248)
			(end -0.494 0.248)
			(stroke
				(width 0.15)
				(type solid)
			)
			(layer "F.Fab")
		)
		(fp_line
			(start -0.494 -0.25)
			(end 0.504 -0.25)
			(stroke
				(width 0.15)
				(type solid)
			)
			(layer "F.Fab")
		)
		(fp_line
			(start 0.504 -0.25)
			(end 0.504 0.248)
			(stroke
				(width 0.15)
				(type solid)
			)
			(layer "F.Fab")
		)
		(fp_text user "${REFERENCE}"
			(at -0.939 4.599 270)
			(layer "F.Fab")
			(effects
				(font
					(size 0.7 0.7)
					(thickness 0.15)
				)
				(justify left bottom)
			)
		)
		(fp_text user "Author: Antmicro"
			(at -0.939 3.399 270)
			(layer "F.Fab")
			(effects
				(font
					(size 0.7 0.7)
					(thickness 0.15)
				)
				(justify left bottom)
			)
		)
		(fp_text user "License: Apache-2.0"
			(at -0.939 5.799 270)
			(layer "F.Fab")
			(effects
				(font
					(size 0.7 0.7)
					(thickness 0.15)
				)
				(justify left bottom)
			)
		)
		(pad "1" smd roundrect
			(at -0.48 0 270)
			(size 0.59 0.64)
			(layers "F.Cu" "F.Mask" "F.Paste")
			(roundrect_rratio 0.25)
			(net 1 "GND")
			(pintype "passive")
		)
		(pad "2" smd roundrect
			(at 0.48 0 270)
			(size 0.59 0.64)
			(layers "F.Cu" "F.Mask" "F.Paste")
			(roundrect_rratio 0.25)
			(net 8 "/HDMI + SD Card/HDMI_CONN_5V")
			(pintype "passive")
		)
	)
	(footprint "antmicro-footprints:C_0603_1608Metric"
		(layer "F.Cu")
		(at 232.65 170.104999 180)
		(descr "Capacitor SMD 0603")
		(tags "capacitor 0603")
		(property "Reference" "C221"
			(at -4.025 -0.395001 0)
			(layer "F.SilkS")
			(effects
				(font
					(size 0.7 0.7)
					(thickness 0.15)
				)
				(justify right bottom)
			)
		)
		(property "Value" "C_22u_0603"
			(at -1.42757 1.770288 0)
			(layer "F.Fab")
			(effects
				(font
					(size 0.7 0.7)
					(thickness 0.15)
				)
				(justify right bottom)
			)
		)
		(property "Datasheet" "https://www.murata.com/products/productdetail?partno=GRM188R60J226MEA0%23"
			(at 0 0 180)
			(layer "F.Fab")
			(hide yes)
			(effects
				(font
					(size 1.27 1.27)
					(thickness 0.15)
				)
			)
		)
		(property "Manufacturer" "Murata"
			(at 0 0 180)
			(unlocked yes)
			(layer "F.Fab")
			(hide yes)
			(effects
				(font
					(size 1 1)
					(thickness 0.15)
				)
			)
		)
		(property "MPN" "GRM188R60J226MEA0D"
			(at 0 0 180)
			(unlocked yes)
			(layer "F.Fab")
			(hide yes)
			(effects
				(font
					(size 1 1)
					(thickness 0.15)
				)
			)
		)
		(property "Val" "22u"
			(at 0 0 180)
			(unlocked yes)
			(layer "F.Fab")
			(hide yes)
			(effects
				(font
					(size 1 1)
					(thickness 0.15)
				)
			)
		)
		(property "License" "Apache-2.0"
			(at 0 0 180)
			(unlocked yes)
			(layer "F.Fab")
			(hide yes)
			(effects
				(font
					(size 1 1)
					(thickness 0.15)
				)
			)
		)
		(property "Author" "Antmicro"
			(at 0 0 180)
			(unlocked yes)
			(layer "F.Fab")
			(hide yes)
			(effects
				(font
					(size 1 1)
					(thickness 0.15)
				)
			)
		)
		(property "Voltage" ""
			(at 0 0 180)
			(unlocked yes)
			(layer "F.Fab")
			(hide yes)
			(effects
				(font
					(size 1 1)
					(thickness 0.15)
				)
			)
		)
		(property "Dielectric" ""
			(at 0 0 180)
			(unlocked yes)
			(layer "F.Fab")
			(hide yes)
			(effects
				(font
					(size 1 1)
					(thickness 0.15)
				)
			)
		)
		(sheetname "/Supply/DC-DC VCCINT/")
		(sheetfile "dc-dc-vccint.kicad_sch")
		(attr smd)
		(fp_line
			(start -0.15 0.4)
			(end 0.15 0.4)
			(stroke
				(width 0.15)
				(type solid)
			)
			(layer "F.SilkS")
		)
		(fp_line
			(start -0.15 -0.4)
			(end 0.15 -0.4)
			(stroke
				(width 0.15)
				(type solid)
			)
			(layer "F.SilkS")
		)
		(fp_rect
			(start -1.25 -0.65)
			(end 1.25 0.65)
			(stroke
				(width 0.05)
				(type solid)
			)
			(fill no)
			(layer "F.CrtYd")
		)
		(fp_rect
			(start -0.8 -0.4)
			(end 0.8 0.4)
			(stroke
				(width 0.15)
				(type solid)
			)
			(fill no)
			(layer "F.Fab")
		)
		(fp_text user "License: Apache-2.0"
			(at -1.682 5.895 180)
			(layer "F.Fab")
			(effects
				(font
					(size 0.7 0.7)
					(thickness 0.15)
				)
				(justify left bottom)
			)
		)
		(fp_text user "Author: Antmicro"
			(at -1.682 4.894 180)
			(layer "F.Fab")
			(effects
				(font
					(size 0.7 0.7)
					(thickness 0.15)
				)
				(justify left bottom)
			)
		)
		(fp_text user "${REFERENCE}"
			(at -1.682 3.895 180)
			(layer "F.Fab")
			(effects
				(font
					(size 0.7 0.7)
					(thickness 0.15)
				)
				(justify left bottom)
			)
		)
		(pad "1" smd roundrect
			(at -0.7 0 180)
			(size 0.8 1)
			(layers "F.Cu" "F.Mask" "F.Paste")
			(roundrect_rratio 0.2)
			(net 1 "GND")
			(pintype "passive")
		)
		(pad "2" smd roundrect
			(at 0.7 0 180)
			(size 0.8 1)
			(layers "F.Cu" "F.Mask" "F.Paste")
			(roundrect_rratio 0.2)
			(net 224 "/Supply/DC-DC VCCINT/0V85_REG1")
			(pintype "passive")
		)
	)
	(footprint "antmicro-footprints:R_0402_1005Metric"
		(layer "F.Cu")
		(at 250.95 182.078 -90)
		(descr "Resistor SMD 0402")
		(tags "resistor SMD 0402")
		(property "Reference" "R15"
			(at -1.278 2.55 90)
			(layer "F.SilkS")
			(effects
				(font
					(size 0.7 0.7)
					(thickness 0.15)
				)
				(justify right bottom)
			)
		)
		(property "Value" "R_0R_0402"
			(at -1.011843 1.772047 90)
			(layer "F.Fab")
			(effects
				(font
					(size 0.7 0.7)
					(thickness 0.15)
				)
				(justify right bottom)
			)
		)
		(property "Datasheet" "https://industrial.panasonic.com/cdbs/www-data/pdf/RDA0000/AOA0000C301.pdf"
			(at 0 0 270)
			(layer "F.Fab")
			(hide yes)
			(effects
				(font
					(size 1.27 1.27)
					(thickness 0.15)
				)
			)
		)
		(property "MPN" "ERJ2GE0R00X"
			(at 0 0 270)
			(unlocked yes)
			(layer "F.Fab")
			(hide yes)
			(effects
				(font
					(size 1 1)
					(thickness 0.15)
				)
			)
		)
		(property "Manufacturer" "Panasonic"
			(at 0 0 270)
			(unlocked yes)
			(layer "F.Fab")
			(hide yes)
			(effects
				(font
					(size 1 1)
					(thickness 0.15)
				)
			)
		)
		(property "License" "Apache-2.0"
			(at 0 0 270)
			(unlocked yes)
			(layer "F.Fab")
			(hide yes)
			(effects
				(font
					(size 1 1)
					(thickness 0.15)
				)
			)
		)
		(property "Author" "Antmicro"
			(at 0 0 270)
			(unlocked yes)
			(layer "F.Fab")
			(hide yes)
			(effects
				(font
					(size 1 1)
					(thickness 0.15)
				)
			)
		)
		(property "Val" "0R"
			(at 0 0 270)
			(unlocked yes)
			(layer "F.Fab")
			(hide yes)
			(effects
				(font
					(size 1 1)
					(thickness 0.15)
				)
			)
		)
		(property "Tolerance" "~"
			(at 0 0 270)
			(unlocked yes)
			(layer "F.Fab")
			(hide yes)
			(effects
				(font
					(size 1 1)
					(thickness 0.15)
				)
			)
		)
		(property "Current" "1A"
			(at 0 0 270)
			(unlocked yes)
			(layer "F.Fab")
			(hide yes)
			(effects
				(font
					(size 1 1)
					(thickness 0.15)
				)
			)
		)
		(sheetname "/I^{2}C + I3C/")
		(sheetfile "i2c.kicad_sch")
		(attr smd)
		(fp_rect
			(start -0.925 -0.47)
			(end 0.925 0.47)
			(stroke
				(width 0.05)
				(type default)
			)
			(fill no)
			(layer "F.CrtYd")
		)
		(fp_rect
			(start -0.5 -0.25)
			(end 0.5 0.25)
			(stroke
				(width 0.15)
				(type solid)
			)
			(fill no)
			(layer "F.Fab")
		)
		(fp_text user "${REFERENCE}"
			(at -0.95 3.168 270)
			(layer "F.Fab")
			(effects
				(font
					(size 0.7 0.7)
					(thickness 0.15)
				)
				(justify left bottom)
			)
		)
		(fp_text user "Author: Antmicro"
			(at -0.95 4.169 270)
			(layer "F.Fab")
			(effects
				(font
					(size 0.7 0.7)
					(thickness 0.15)
				)
				(justify left bottom)
			)
		)
		(fp_text user "License: Apache-2.0"
			(at -0.95 5.169 270)
			(layer "F.Fab")
			(effects
				(font
					(size 0.7 0.7)
					(thickness 0.15)
				)
				(justify left bottom)
			)
		)
		(pad "1" smd roundrect
			(at -0.48 0 270)
			(size 0.59 0.64)
			(layers "F.Cu" "F.Mask" "F.Paste")
			(roundrect_rratio 0.25)
			(net 775 "Net-(Q24-S)")
			(pintype "passive")
		)
		(pad "2" smd roundrect
			(at 0.48 0 270)
			(size 0.59 0.64)
			(layers "F.Cu" "F.Mask" "F.Paste")
			(roundrect_rratio 0.25)
			(net 797 "+1V8")
			(pintype "passive")
		)
	)
	(footprint "antmicro-footprints:C_0805_2012Metric"
		(layer "F.Cu")
		(at 230.01 185.8)
		(descr "Capacitor SMD 0805")
		(tags "capacitor SMD 0805")
		(property "Reference" "C313"
			(at 1.915 0.45 0)
			(layer "F.SilkS")
			(effects
				(font
					(size 0.7 0.7)
					(thickness 0.15)
				)
				(justify left bottom)
			)
		)
		(property "Value" "C_22u_25V_0805"
			(at -2.055717 1.963152 0)
			(layer "F.Fab")
			(effects
				(font
					(size 0.7 0.7)
					(thickness 0.15)
				)
				(justify left bottom)
			)
		)
		(property "Datasheet" "https://product.samsungsem.com/mlcc/CL21A226MAYNNN.do"
			(at 0 0 0)
			(layer "F.Fab")
			(hide yes)
			(effects
				(font
					(size 1.27 1.27)
					(thickness 0.15)
				)
			)
		)
		(property "MPN" "CL21A226MAYNNNE"
			(at 0 0 0)
			(unlocked yes)
			(layer "F.Fab")
			(hide yes)
			(effects
				(font
					(size 1 1)
					(thickness 0.15)
				)
			)
		)
		(property "Manufacturer" "Samsung Electro-Mechanics"
			(at 0 0 0)
			(unlocked yes)
			(layer "F.Fab")
			(hide yes)
			(effects
				(font
					(size 1 1)
					(thickness 0.15)
				)
			)
		)
		(property "License" "Apache-2.0"
			(at 0 0 0)
			(unlocked yes)
			(layer "F.Fab")
			(hide yes)
			(effects
				(font
					(size 1 1)
					(thickness 0.15)
				)
			)
		)
		(property "Author" "Antmicro"
			(at 0 0 0)
			(unlocked yes)
			(layer "F.Fab")
			(hide yes)
			(effects
				(font
					(size 1 1)
					(thickness 0.15)
				)
			)
		)
		(property "Val" "22u"
			(at 0 0 0)
			(unlocked yes)
			(layer "F.Fab")
			(hide yes)
			(effects
				(font
					(size 1 1)
					(thickness 0.15)
				)
			)
		)
		(property "Voltage" "25V"
			(at 0 0 0)
			(unlocked yes)
			(layer "F.Fab")
			(hide yes)
			(effects
				(font
					(size 1 1)
					(thickness 0.15)
				)
			)
		)
		(property "Dielectric" "X5R"
			(at 0 0 0)
			(unlocked yes)
			(layer "F.Fab")
			(hide yes)
			(effects
				(font
					(size 1 1)
					(thickness 0.15)
				)
			)
		)
		(property "Public" "False"
			(at 0 0 0)
			(unlocked yes)
			(layer "F.Fab")
			(hide yes)
			(effects
				(font
					(size 1 1)
					(thickness 0.15)
				)
			)
		)
		(sheetname "/Supply/DC-DC VCCINT/")
		(sheetfile "dc-dc-vccint.kicad_sch")
		(attr smd exclude_from_bom)
		(fp_line
			(start -0.3 -0.7)
			(end 0.3 -0.7)
			(stroke
				(width 0.15)
				(type solid)
			)
			(layer "F.SilkS")
		)
		(fp_line
			(start -0.3 0.7)
			(end 0.3 0.7)
			(stroke
				(width 0.15)
				(type solid)
			)
			(layer "F.SilkS")
		)
		(fp_rect
			(start 1.95 -0.9)
			(end -1.95 0.9)
			(stroke
				(width 0.05)
				(type default)
			)
			(fill no)
			(layer "F.CrtYd")
		)
		(fp_rect
			(start -0.95 -0.675)
			(end 0.95 0.675)
			(stroke
				(width 0.15)
				(type solid)
			)
			(fill no)
			(layer "F.Fab")
		)
		(fp_text user "Author: Antmicro"
			(at -1.9 5.947 0)
			(layer "F.Fab")
			(effects
				(font
					(size 0.7 0.7)
					(thickness 0.15)
				)
				(justify left bottom)
			)
		)
		(fp_text user "License: Apache-2.0"
			(at -1.9 4.947 0)
			(layer "F.Fab")
			(effects
				(font
					(size 0.7 0.7)
					(thickness 0.15)
				)
				(justify left bottom)
			)
		)
		(fp_text user "${REFERENCE}"
			(at -1.9 3.947 0)
			(layer "F.Fab")
			(effects
				(font
					(size 0.7 0.7)
					(thickness 0.15)
				)
				(justify left bottom)
			)
		)
		(pad "1" smd roundrect
			(at -1.1 0)
			(size 1.2 1.3)
			(layers "F.Cu" "F.Mask" "F.Paste")
			(roundrect_rratio 0.25)
			(net 1 "GND")
			(pintype "passive")
		)
		(pad "2" smd roundrect
			(at 1.1 0)
			(size 1.2 1.3)
			(layers "F.Cu" "F.Mask" "F.Paste")
			(roundrect_rratio 0.25)
			(net 35 "VDC")
			(pintype "passive")
		)
	)
	(footprint "antmicro-footprints:SW_KMR211NGLFS_SMD"
		(layer "F.Cu")
		(at 260.574499 144.249 90)
		(property "Reference" "SW3"
			(at -1.181 -3.664499 90)
			(layer "F.SilkS")
			(hide yes)
			(effects
				(font
					(size 0.7 0.7)
					(thickness 0.15)
				)
				(justify left bottom)
			)
		)
		(property "Value" "SW_KMR211NGLFS_SMD"
			(at 0 2.8 90)
			(layer "F.Fab")
			(effects
				(font
					(size 0.7 0.7)
					(thickness 0.15)
				)
				(justify left bottom)
			)
		)
		(property "Datasheet" "http://www.farnell.com/datasheets/2631211.pdf"
			(at 0 0 90)
			(layer "F.Fab")
			(hide yes)
			(effects
				(font
					(size 1.27 1.27)
					(thickness 0.15)
				)
			)
		)
		(property "MPN" "KMR211NGLFS"
			(at 0 0 90)
			(unlocked yes)
			(layer "F.Fab")
			(hide yes)
			(effects
				(font
					(size 1 1)
					(thickness 0.15)
				)
			)
		)
		(property "Manufacturer" "C&K"
			(at 0 0 90)
			(unlocked yes)
			(layer "F.Fab")
			(hide yes)
			(effects
				(font
					(size 1 1)
					(thickness 0.15)
				)
			)
		)
		(property "Author" "Antmicro"
			(at 0 0 90)
			(unlocked yes)
			(layer "F.Fab")
			(hide yes)
			(effects
				(font
					(size 1 1)
					(thickness 0.15)
				)
			)
		)
		(property "License" "Apache-2.0"
			(at 0 0 90)
			(unlocked yes)
			(layer "F.Fab")
			(hide yes)
			(effects
				(font
					(size 1 1)
					(thickness 0.15)
				)
			)
		)
		(sheetname "/DDR5 RDIMM/")
		(sheetfile "ddr5-rdimm.kicad_sch")
		(attr smd)
		(fp_line
			(start 2.101 -1.6)
			(end -2.1 -1.6)
			(stroke
				(width 0.15)
				(type solid)
			)
			(layer "F.SilkS")
		)
		(fp_line
			(start -2.1 -1.6)
			(end -2.1 -1.499)
			(stroke
				(width 0.15)
				(type solid)
			)
			(layer "F.SilkS")
		)
		(fp_line
			(start 2.101 -1.58)
			(end 2.101 -1.459)
			(stroke
				(width 0.15)
				(type solid)
			)
			(layer "F.SilkS")
		)
		(fp_line
			(start 2.101 1.601)
			(end 2.101 1.48)
			(stroke
				(width 0.15)
				(type solid)
			)
			(layer "F.SilkS")
		)
		(fp_line
			(start 2.101 1.601)
			(end -2.1 1.601)
			(stroke
				(width 0.15)
				(type solid)
			)
			(layer "F.SilkS")
		)
		(fp_line
			(start -2.1 1.601)
			(end -2.1 1.48)
			(stroke
				(width 0.15)
				(type solid)
			)
			(layer "F.SilkS")
		)
		(fp_rect
			(start 2.751 1.75)
			(end -2.748 -1.749)
			(stroke
				(width 0.05)
				(type solid)
			)
			(fill no)
			(layer "F.CrtYd")
		)
		(fp_line
			(start 2.101 -1.6)
			(end -2.1 -1.6)
			(stroke
				(width 0.15)
				(type solid)
			)
			(layer "F.Fab")
		)
		(fp_line
			(start -2.1 -1.6)
			(end -2.1 1.601)
			(stroke
				(width 0.15)
				(type solid)
			)
			(layer "F.Fab")
		)
		(fp_line
			(start -0.248 -0.8)
			(end 0.25 -0.8)
			(stroke
				(width 0.15)
				(type solid)
			)
			(layer "F.Fab")
		)
		(fp_line
			(start 0.25 0.802)
			(end -0.248 0.802)
			(stroke
				(width 0.15)
				(type solid)
			)
			(layer "F.Fab")
		)
		(fp_line
			(start 2.101 1.601)
			(end 2.101 -1.6)
			(stroke
				(width 0.15)
				(type solid)
			)
			(layer "F.Fab")
		)
		(fp_line
			(start -2.1 1.601)
			(end 2.101 1.601)
			(stroke
				(width 0.15)
				(type solid)
			)
			(layer "F.Fab")
		)
		(fp_arc
			(start 0.25 -0.8)
			(mid 1.051001 0.001)
			(end 0.25 0.802)
			(stroke
				(width 0.15)
				(type solid)
			)
			(layer "F.Fab")
		)
		(fp_arc
			(start -0.248 0.802)
			(mid -1.050001 0.001)
			(end -0.248 -0.8)
			(stroke
				(width 0.15)
				(type solid)
			)
			(layer "F.Fab")
		)
		(fp_text user "${REFERENCE}"
			(at -3 4.25 90)
			(layer "F.Fab")
			(effects
				(font
					(size 0.7 0.7)
					(thickness 0.15)
				)
				(justify left bottom)
			)
		)
		(fp_text user "Author: Antmicro"
			(at -3 5.5 90)
			(layer "F.Fab")
			(effects
				(font
					(size 0.7 0.7)
					(thickness 0.15)
				)
				(justify left bottom)
			)
		)
		(fp_text user "License: Apache-2.0"
			(at -3 6.75 90)
			(layer "F.Fab")
			(effects
				(font
					(size 0.7 0.7)
					(thickness 0.15)
				)
				(justify left bottom)
			)
		)
		(pad "1" smd rect
			(at -2.048 -0.8 270)
			(size 0.9 1)
			(layers "F.Cu" "F.Mask" "F.Paste")
			(net 1 "GND")
			(pinfunction "1")
			(pintype "passive")
		)
		(pad "2" smd rect
			(at 2.05 -0.8 270)
			(size 0.9 1)
			(layers "F.Cu" "F.Mask" "F.Paste")
			(net 1 "GND")
			(pinfunction "2")
			(pintype "passive")
		)
		(pad "3" smd rect
			(at -2.048 0.802 270)
			(size 0.9 1)
			(layers "F.Cu" "F.Mask" "F.Paste")
			(net 69 "HOT_SWAP_BUTTON")
			(pinfunction "3")
			(pintype "passive")
		)
		(pad "4" smd rect
			(at 2.05 0.802 270)
			(size 0.9 1)
			(layers "F.Cu" "F.Mask" "F.Paste")
			(net 69 "HOT_SWAP_BUTTON")
			(pinfunction "4")
			(pintype "passive")
		)
	)
)
